(kicad_pcb
	(version 20221018)
	(generator pcbnew)
	(general
    (thickness 1.7403)
  )
	(paper "A4")
	(title_block
    (title "Data Center RDIMM DDR4 Tester")
    (date "2024-09-30")
    (rev "1.2.4")
		(comment 9 "footprints 266-274 of 690")
	)
	(layers
    (0 "F.Cu" signal)
    (1 "In1.Cu" power)
    (2 "In2.Cu" signal)
    (3 "In3.Cu" power)
    (4 "In4.Cu" power)
    (5 "In5.Cu" signal)
    (6 "In6.Cu" power)
    (7 "In7.Cu" signal)
    (8 "In8.Cu" power)
    (9 "In9.Cu" signal)
    (10 "In10.Cu" power)
    (31 "B.Cu" signal)
    (32 "B.Adhes" user "B.Adhesive")
    (33 "F.Adhes" user "F.Adhesive")
    (34 "B.Paste" user)
    (35 "F.Paste" user)
    (36 "B.SilkS" user "B.Silkscreen")
    (37 "F.SilkS" user "F.Silkscreen")
    (38 "B.Mask" user)
    (39 "F.Mask" user)
    (40 "Dwgs.User" user "User.Drawings")
    (41 "Cmts.User" user "User.Comments")
    (42 "Eco1.User" user "User.Eco1")
    (43 "Eco2.User" user "User.Eco2")
    (44 "Edge.Cuts" user)
    (45 "Margin" user)
    (46 "B.CrtYd" user "B.Courtyard")
    (47 "F.CrtYd" user "F.Courtyard")
    (48 "B.Fab" user)
    (49 "F.Fab" user)
  )
	(footprint "data-center-rdimm-ddr4-tester-footprints:SOT-353" (layer "F.Cu")
    (at 225.8 122.8 90)
    (descr "5-lead Small Outline SMT package (aka SC-70-5, SC-88A or TSSOP5): reflow soldering footprint")
    (tags "SOT-353 sot353 SC-70-5 sc70 SC-88A sc88a TSSOP5")
    (property "Author" "Antmicro")
    (property "License" "Apache-2.0")
    (property "MPN" "SN74LVC1G240DCKR")
    (property "Manufacturer" "Texas Instruments")
    (property "Sheetfile" "supply.kicad_sch")
    (property "Sheetname" "Supply")
    (property "ki_description" "Single Inverting Buffer/Driver With 3-State Output")
    (attr smd)
    (fp_text reference "U27" (at 1.42 -1.93) (layer "F.SilkS")
        (effects (font (size 0.7 0.7) (thickness 0.15)) (justify left bottom))
    )
    (fp_text value "SN74LVC1G240_SC70" (at 0 2.4 90) (layer "F.Fab") hide
        (effects (font (size 0.7 0.7) (thickness 0.15)) (justify left bottom))
    )
    (fp_text user "License: Apache-2.0" (at -1.206 6.427 90) (layer "F.Fab") hide
        (effects (font (size 0.7 0.7) (thickness 0.15)) (justify left bottom))
    )
    (fp_text user "${REFERENCE}" (at -1.206 4.027 90) (layer "F.Fab") hide
        (effects (font (size 0.7 0.7) (thickness 0.15)) (justify left bottom))
    )
    (fp_text user "Author: Antmicro" (at -1.206 5.227 90) (layer "F.Fab") hide
        (effects (font (size 0.7 0.7) (thickness 0.15)) (justify left bottom))
    )
    (fp_line (start -1.15 0.7) (end -1.15 -0.65)
      (stroke (width 0.15) (type solid)) (layer "F.SilkS"))
    (fp_line (start 1.15 0.7) (end 1.144 -0.65)
      (stroke (width 0.15) (type solid)) (layer "F.SilkS"))
    (fp_circle (center -0.762 1.6256) (end -0.712 1.6256)
      (stroke (width 0.15) (type solid)) (fill solid) (layer "F.SilkS"))
    (fp_rect (start 1.25 -1.46) (end -1.25 1.45)
      (stroke (width 0.05) (type solid)) (fill none) (layer "F.CrtYd"))
    (fp_line (start -1.006 -0.657) (end 0.993 -0.657)
      (stroke (width 0.15) (type solid)) (layer "F.Fab"))
    (fp_line (start -1.006 0.293) (end -1.006 -0.657)
      (stroke (width 0.15) (type solid)) (layer "F.Fab"))
    (fp_line (start -1.006 0.293) (end -0.706 0.593)
      (stroke (width 0.15) (type solid)) (layer "F.Fab"))
    (fp_line (start 0.993 -0.657) (end 0.993 0.593)
      (stroke (width 0.15) (type solid)) (layer "F.Fab"))
    (fp_line (start 0.993 0.593) (end -0.706 0.593)
      (stroke (width 0.15) (type solid)) (layer "F.Fab"))
    (pad "1" smd roundrect (at -0.756 0.893 180) (size 0.6 0.6) (layers "F.Cu" "F.Paste" "F.Mask") (roundrect_rratio 0.25)
      (net 108 "Net-(U27-~{OE})") (pinfunction "~{OE}") (pintype "input"))
    (pad "2" smd roundrect (at -0.006 0.893 180) (size 0.6 0.4) (layers "F.Cu" "F.Paste" "F.Mask") (roundrect_rratio 0.25)
      (net 859 "/Supply/OUT") (pinfunction "A") (pintype "input"))
    (pad "3" smd roundrect (at 0.743 0.893 180) (size 0.6 0.6) (layers "F.Cu" "F.Paste" "F.Mask") (roundrect_rratio 0.25)
      (net 9 "GND") (pinfunction "GND") (pintype "power_in"))
    (pad "4" smd roundrect (at 0.743 -0.907 180) (size 0.6 0.6) (layers "F.Cu" "F.Paste" "F.Mask") (roundrect_rratio 0.25)
      (net 584 "Net-(Q12-G)") (pinfunction "Y") (pintype "output"))
    (pad "5" smd roundrect (at -0.756 -0.907 180) (size 0.6 0.6) (layers "F.Cu" "F.Paste" "F.Mask") (roundrect_rratio 0.25)
      (net 846 "5V_ON_OFF") (pinfunction "V_{CC}") (pintype "power_in"))
  )
	(footprint "data-center-rdimm-ddr4-tester-footprints:R_0402_1005Metric" (layer "F.Cu")
    (at 122.525 62.95)
    (descr "Resistor SMD 0402")
    (tags "resistor SMD 0402")
    (property "Author" "Antmicro")
    (property "Current" "1A")
    (property "License" "Apache-2.0")
    (property "MPN" "ERJ2GE0R00X")
    (property "Manufacturer" "Panasonic")
    (property "Sheetfile" "DDR4.kicad_sch")
    (property "Sheetname" "DDR4")
    (property "Tolerance" "")
    (property "Val" "0R")
    (property "ki_description" "0R resistor in 0402 package with unspecified tolerance")
    (attr smd)
    (fp_text reference "R158" (at 0 -0.7) (layer "F.SilkS")
        (effects (font (size 0.7 0.7) (thickness 0.15)) (justify left bottom))
    )
    (fp_text value "R_0R_0402" (at 0 1.4) (layer "F.Fab") hide
        (effects (font (size 0.7 0.7) (thickness 0.15)) (justify left bottom))
    )
    (fp_text user "Author: Antmicro" (at -0.95 4.169) (layer "F.Fab") hide
        (effects (font (size 0.7 0.7) (thickness 0.15)) (justify left bottom))
    )
    (fp_text user "${REFERENCE}" (at -0.95 3.168) (layer "F.Fab") hide
        (effects (font (size 0.7 0.7) (thickness 0.15)) (justify left bottom))
    )
    (fp_text user "License: Apache-2.0" (at -0.95 5.169) (layer "F.Fab") hide
        (effects (font (size 0.7 0.7) (thickness 0.15)) (justify left bottom))
    )
    (fp_rect (start -0.93 -0.47) (end 0.93 0.47)
      (stroke (width 0.05) (type solid)) (fill none) (layer "F.CrtYd"))
    (fp_rect (start -0.5 -0.25) (end 0.5 0.25)
      (stroke (width 0.15) (type solid)) (fill none) (layer "F.Fab"))
    (pad "1" smd roundrect (at -0.485 0) (size 0.59 0.64) (layers "F.Cu" "F.Paste" "F.Mask") (roundrect_rratio 0.25)
      (net 184 "VPP") (pintype "passive"))
    (pad "2" smd roundrect (at 0.485 0) (size 0.59 0.64) (layers "F.Cu" "F.Paste" "F.Mask") (roundrect_rratio 0.25)
      (net 185 "VDDSPD") (pintype "passive"))
  )
	(footprint "data-center-rdimm-ddr4-tester-footprints:R_0402_1005Metric" (layer "F.Cu")
    (at 246.042902 123.36 180)
    (descr "Resistor SMD 0402")
    (tags "resistor SMD 0402")
    (property "Author" "Antmicro")
    (property "License" "Apache-2.0")
    (property "MPN" "CR0402-FX-33R0GLF")
    (property "Manufacturer" "Bourns")
    (property "Sheetfile" "fmc_hpc.kicad_sch")
    (property "Sheetname" "FMC HPC")
    (property "Tolerance" "1%")
    (property "Val" "33R")
    (property "ki_description" "33R resistor in 0402 package with 1% tolerance")
    (attr smd)
    (fp_text reference "R152" (at -0.697098 -0.37 180) (layer "F.SilkS")
        (effects (font (size 0.7 0.7) (thickness 0.15)) (justify left bottom))
    )
    (fp_text value "R_33R_0402" (at 0 1.4 180) (layer "F.Fab") hide
        (effects (font (size 0.7 0.7) (thickness 0.15)) (justify left bottom))
    )
    (fp_text user "${REFERENCE}" (at -0.95 3.168 180) (layer "F.Fab") hide
        (effects (font (size 0.7 0.7) (thickness 0.15)) (justify left bottom))
    )
    (fp_text user "License: Apache-2.0" (at -0.95 5.169 180) (layer "F.Fab") hide
        (effects (font (size 0.7 0.7) (thickness 0.15)) (justify left bottom))
    )
    (fp_text user "Author: Antmicro" (at -0.95 4.169 180) (layer "F.Fab") hide
        (effects (font (size 0.7 0.7) (thickness 0.15)) (justify left bottom))
    )
    (fp_rect (start -0.93 -0.47) (end 0.93 0.47)
      (stroke (width 0.05) (type solid)) (fill none) (layer "F.CrtYd"))
    (fp_rect (start -0.5 -0.25) (end 0.5 0.25)
      (stroke (width 0.15) (type solid)) (fill none) (layer "F.Fab"))
    (pad "1" smd roundrect (at -0.485 0 180) (size 0.59 0.64) (layers "F.Cu" "F.Paste" "F.Mask") (roundrect_rratio 0.25)
      (net 899 "/FMC HPC/GTR_REFCLK3_R_P") (pintype "passive"))
    (pad "2" smd roundrect (at 0.485 0 180) (size 0.59 0.64) (layers "F.Cu" "F.Paste" "F.Mask") (roundrect_rratio 0.25)
      (net 895 "GTR_REFCLK3_C_P") (pintype "passive"))
  )
	(footprint "data-center-rdimm-ddr4-tester-footprints:C_0402_1005Metric" (layer "F.Cu")
    (at 225.4 124.6)
    (descr "Capacitor SMD 0402")
    (tags "capacitor SMD 0402")
    (property "Author" "Antmicro")
    (property "Dielectric" "X5R")
    (property "License" "Apache-2.0")
    (property "MPN" "GRM155R61H104KE14D")
    (property "Manufacturer" "Murata")
    (property "Sheetfile" "supply.kicad_sch")
    (property "Sheetname" "Supply")
    (property "Val" "100n")
    (property "Voltage" "50V")
    (property "ki_description" " ")
    (attr smd)
    (fp_text reference "C282" (at -1.11 1.33) (layer "F.SilkS")
        (effects (font (size 0.7 0.7) (thickness 0.15)) (justify left bottom))
    )
    (fp_text value "C_100n_0402" (at 0 1.4) (layer "F.Fab") hide
        (effects (font (size 0.7 0.7) (thickness 0.15)) (justify left bottom))
    )
    (fp_text user "${REFERENCE}" (at -0.932 3.168) (layer "F.Fab") hide
        (effects (font (size 0.7 0.7) (thickness 0.15)) (justify left bottom))
    )
    (fp_text user "License: Apache-2.0" (at -0.932 5.17) (layer "F.Fab") hide
        (effects (font (size 0.7 0.7) (thickness 0.15)) (justify left bottom))
    )
    (fp_text user "Author: Antmicro" (at -0.932 4.17) (layer "F.Fab") hide
        (effects (font (size 0.7 0.7) (thickness 0.15)) (justify left bottom))
    )
    (fp_rect (start -0.94 -0.47) (end 0.94 0.47)
      (stroke (width 0.05) (type solid)) (fill none) (layer "F.CrtYd"))
    (fp_rect (start -0.499 -0.249) (end 0.499 0.249)
      (stroke (width 0.15) (type solid)) (fill none) (layer "F.Fab"))
    (pad "1" smd roundrect (at -0.484 0) (size 0.59 0.64) (layers "F.Cu" "F.Paste" "F.Mask") (roundrect_rratio 0.25)
      (net 846 "5V_ON_OFF") (pintype "passive"))
    (pad "2" smd roundrect (at 0.484 0) (size 0.59 0.64) (layers "F.Cu" "F.Paste" "F.Mask") (roundrect_rratio 0.25)
      (net 9 "GND") (pintype "passive"))
  )
	(footprint "data-center-rdimm-ddr4-tester-footprints:NetTie-2_SMD_Pad0.127mm" (layer "F.Cu")
    (at 153.17 121.7)
    (descr "Net tie, 2 pin, 0.127mm  SMD pads")
    (tags "net tie")
    (property "Author" "Antmicro")
    (property "License" "Apache-2.0")
    (property "MPN" "")
    (property "Manufacturer" "")
    (property "Sheetfile" "supply.kicad_sch")
    (property "Sheetname" "Supply")
    (property "ki_description" "Net tie, 2 pins")
    (property "ki_keywords" "net tie short")
    (attr through_hole exclude_from_pos_files)
    (net_tie_pad_groups "1, 2")
    (fp_text reference "NT16" (at -0.128 -1.345) (layer "F.SilkS") hide
        (effects (font (size 0.7 0.7) (thickness 0.15)) (justify left bottom))
    )
    (fp_text value "Net-Tie_2" (at 0 1.199) (layer "F.Fab") hide
        (effects (font (size 0.7 0.7) (thickness 0.15)) (justify left bottom))
    )
    (fp_text user "${REFERENCE}" (at -0.128 3.2) (layer "F.Fab") hide
        (effects (font (size 0.7 0.7) (thickness 0.15)) (justify left bottom))
    )
    (fp_text user "Author: Antmicro" (at -0.128 4.4) (layer "F.Fab") hide
        (effects (font (size 0.7 0.7) (thickness 0.15)) (justify left bottom))
    )
    (fp_text user "License: Apache-2.0" (at -0.128 5.6) (layer "F.Fab") hide
        (effects (font (size 0.7 0.7) (thickness 0.15)) (justify left bottom))
    )
    (fp_poly
      (pts
        (xy -0.0635 -0.0635)
        (xy 0.0625 -0.0635)
        (xy 0.0625 0.0635)
        (xy -0.0635 0.0635)
      )

      (stroke (width 0) (type solid)) (fill solid) (layer "F.Cu"))
    (pad "1" smd roundrect (at -0.127 0 180) (size 0.127 0.127) (layers "F.Cu") (roundrect_rratio 0.5)
      (chamfer_ratio 0) (chamfer top_left bottom_left)
      (net 806 "/Supply/VCC1V2_SEN_-") (pinfunction "1") (pintype "passive"))
    (pad "2" smd roundrect (at 0.126 0) (size 0.127 0.127) (layers "F.Cu") (roundrect_rratio 0.5)
      (chamfer_ratio 0) (chamfer top_left bottom_left)
      (net 306 "1V2_SYS") (pinfunction "2") (pintype "passive"))
  )
	(footprint "data-center-rdimm-ddr4-tester-footprints:C_0402_1005Metric" (layer "F.Cu")
    (at 221.85 126.4 180)
    (descr "Capacitor SMD 0402")
    (tags "capacitor SMD 0402")
    (property "Author" "Antmicro")
    (property "DNP" "DNP")
    (property "Dielectric" "")
    (property "License" "Apache-2.0")
    (property "MPN" "C1005X6S1A105K050BC")
    (property "Manufacturer" "TDK")
    (property "Sheetfile" "interfaces.kicad_sch")
    (property "Sheetname" "Interfaces")
    (property "Val" "1u")
    (property "Voltage" "")
    (property "dnp" "")
    (property "exclude_from_bom" "")
    (property "ki_description" " ")
    (attr exclude_from_pos_files exclude_from_bom)
    (fp_text reference "C226" (at -0.83 -0.73 180) (layer "F.SilkS")
        (effects (font (size 0.7 0.7) (thickness 0.15)) (justify left bottom))
    )
    (fp_text value "C_1u_0402" (at 0 1.4 180) (layer "F.Fab") hide
        (effects (font (size 0.7 0.7) (thickness 0.15)) (justify left bottom))
    )
    (fp_text user "${REFERENCE}" (at -0.932 3.168 180) (layer "F.Fab") hide
        (effects (font (size 0.7 0.7) (thickness 0.15)) (justify left bottom))
    )
    (fp_text user "Author: Antmicro" (at -0.932 4.17 180) (layer "F.Fab") hide
        (effects (font (size 0.7 0.7) (thickness 0.15)) (justify left bottom))
    )
    (fp_text user "License: Apache-2.0" (at -0.932 5.17 180) (layer "F.Fab") hide
        (effects (font (size 0.7 0.7) (thickness 0.15)) (justify left bottom))
    )
    (fp_rect (start -0.94 -0.47) (end 0.94 0.47)
      (stroke (width 0.05) (type solid)) (fill none) (layer "F.CrtYd"))
    (fp_rect (start -0.499 -0.249) (end 0.499 0.249)
      (stroke (width 0.15) (type solid)) (fill none) (layer "F.Fab"))
    (pad "1" smd roundrect (at -0.484 0 180) (size 0.59 0.64) (layers "F.Cu" "F.Paste" "F.Mask") (roundrect_rratio 0.25)
      (net 149 "HOT_SWAP_BUTTON") (pintype "passive"))
    (pad "2" smd roundrect (at 0.484 0 180) (size 0.59 0.64) (layers "F.Cu" "F.Paste" "F.Mask") (roundrect_rratio 0.25)
      (net 9 "GND") (pintype "passive"))
  )
	(footprint "data-center-rdimm-ddr4-tester-footprints:NetTie-2_SMD_Pad0.127mm" (layer "F.Cu")
    (at 151.43 121.7 180)
    (descr "Net tie, 2 pin, 0.127mm  SMD pads")
    (tags "net tie")
    (property "Author" "Antmicro")
    (property "License" "Apache-2.0")
    (property "MPN" "")
    (property "Manufacturer" "")
    (property "Sheetfile" "supply.kicad_sch")
    (property "Sheetname" "Supply")
    (property "ki_description" "Net tie, 2 pins")
    (property "ki_keywords" "net tie short")
    (attr through_hole exclude_from_pos_files)
    (net_tie_pad_groups "1, 2")
    (fp_text reference "NT15" (at -0.128 -1.345 180) (layer "F.SilkS") hide
        (effects (font (size 0.7 0.7) (thickness 0.15)) (justify left bottom))
    )
    (fp_text value "Net-Tie_2" (at 0 1.199 180) (layer "F.Fab") hide
        (effects (font (size 0.7 0.7) (thickness 0.15)) (justify left bottom))
    )
    (fp_text user "License: Apache-2.0" (at -0.128 5.6 180) (layer "F.Fab") hide
        (effects (font (size 0.7 0.7) (thickness 0.15)) (justify left bottom))
    )
    (fp_text user "${REFERENCE}" (at -0.128 3.2 180) (layer "F.Fab") hide
        (effects (font (size 0.7 0.7) (thickness 0.15)) (justify left bottom))
    )
    (fp_text user "Author: Antmicro" (at -0.128 4.4 180) (layer "F.Fab") hide
        (effects (font (size 0.7 0.7) (thickness 0.15)) (justify left bottom))
    )
    (fp_poly
      (pts
        (xy -0.0635 -0.0635)
        (xy 0.0625 -0.0635)
        (xy 0.0625 0.0635)
        (xy -0.0635 0.0635)
      )

      (stroke (width 0) (type solid)) (fill solid) (layer "F.Cu"))
    (pad "1" smd roundrect (at -0.127 0) (size 0.127 0.127) (layers "F.Cu") (roundrect_rratio 0.5)
      (chamfer_ratio 0) (chamfer top_left bottom_left)
      (net 805 "/Supply/VCC1V2_SEN_+") (pinfunction "1") (pintype "passive"))
    (pad "2" smd roundrect (at 0.126 0 180) (size 0.127 0.127) (layers "F.Cu") (roundrect_rratio 0.5)
      (chamfer_ratio 0) (chamfer top_left bottom_left)
      (net 176 "VCC1V2") (pinfunction "2") (pintype "passive"))
  )
	(footprint "data-center-rdimm-ddr4-tester-footprints:R_0402_1005Metric" (layer "F.Cu")
    (at 201.9 113.7 -90)
    (descr "Resistor SMD 0402")
    (tags "resistor SMD 0402")
    (property "Author" "Antmicro")
    (property "License" "Apache-2.0")
    (property "MPN" "CR0402-FX-3242GLF")
    (property "Manufacturer" "Bourns")
    (property "Sheetfile" "ethernet.kicad_sch")
    (property "Sheetname" "Ethernet")
    (property "Tolerance" "1%")
    (property "Val" "32k4")
    (property "ki_description" "32k4 resistor in 0402 package with 1% tolerance")
    (attr smd)
    (fp_text reference "R180" (at 1.38 0.57 -90) (layer "F.SilkS")
        (effects (font (size 0.7 0.7) (thickness 0.15)) (justify left bottom))
    )
    (fp_text value "R_32k4_0402" (at 0 1.4 -90) (layer "F.Fab") hide
        (effects (font (size 0.7 0.7) (thickness 0.15)) (justify left bottom))
    )
    (fp_text user "License: Apache-2.0" (at -0.95 5.169 -90) (layer "F.Fab") hide
        (effects (font (size 0.7 0.7) (thickness 0.15)) (justify left bottom))
    )
    (fp_text user "${REFERENCE}" (at -0.95 3.168 -90) (layer "F.Fab") hide
        (effects (font (size 0.7 0.7) (thickness 0.15)) (justify left bottom))
    )
    (fp_text user "Author: Antmicro" (at -0.95 4.169 -90) (layer "F.Fab") hide
        (effects (font (size 0.7 0.7) (thickness 0.15)) (justify left bottom))
    )
    (fp_rect (start -0.93 -0.47) (end 0.93 0.47)
      (stroke (width 0.05) (type solid)) (fill none) (layer "F.CrtYd"))
    (fp_rect (start -0.5 -0.25) (end 0.5 0.25)
      (stroke (width 0.15) (type solid)) (fill none) (layer "F.Fab"))
    (pad "1" smd roundrect (at -0.485 0 270) (size 0.59 0.64) (layers "F.Cu" "F.Paste" "F.Mask") (roundrect_rratio 0.25)
      (net 609 "Net-(D15-Pad1)") (pintype "passive"))
    (pad "2" smd roundrect (at 0.485 0 270) (size 0.59 0.64) (layers "F.Cu" "F.Paste" "F.Mask") (roundrect_rratio 0.25)
      (net 360 "/Ethernet/VDD") (pintype "passive"))
  )
	(footprint "data-center-rdimm-ddr4-tester-footprints:R_1206_3216Metric" (layer "F.Cu")
    (at 112.25 108.95 180)
    (property "Author" "Antmicro")
    (property "License" "Apache-2.0")
    (property "MPN" "RL1206FR-7W0R01L")
    (property "Manufacturer" "Yaego")
    (property "Sheetfile" "supply.kicad_sch")
    (property "Sheetname" "Supply")
    (property "Tolerance" "1%")
    (property "Val" "0R01")
    (property "ki_description" "0R01 resistor in 1206 package with unspecified tolerance")
    (attr smd)
    (fp_text reference "R202" (at 3.26 1.15 180) (layer "F.SilkS")
        (effects (font (size 0.7 0.7) (thickness 0.15)) (justify left bottom))
    )
    (fp_text value "R_0R01_1206" (at 0 2 180) (layer "F.Fab") hide
        (effects (font (size 0.7 0.7) (thickness 0.15)) (justify left bottom))
    )
    (fp_text user "License: Apache-2.0" (at -2.401 6.3 180) (layer "F.Fab") hide
        (effects (font (size 0.7 0.7) (thickness 0.15)) (justify left bottom))
    )
    (fp_text user "${REFERENCE}" (at -2.401 3.5 180) (layer "F.Fab") hide
        (effects (font (size 0.7 0.7) (thickness 0.15)) (justify left bottom))
    )
    (fp_text user "Author: Antmicro" (at -2.401 4.899 180) (layer "F.Fab") hide
        (effects (font (size 0.7 0.7) (thickness 0.15)) (justify left bottom))
    )
    (fp_line (start 0 -0.902) (end -0.5 -0.902)
      (stroke (width 0.15) (type solid)) (layer "F.SilkS"))
    (fp_line (start 0 -0.902) (end 0.498 -0.902)
      (stroke (width 0.15) (type solid)) (layer "F.SilkS"))
    (fp_line (start 0 0.9) (end -0.5 0.9)
      (stroke (width 0.15) (type solid)) (layer "F.SilkS"))
    (fp_line (start 0 0.9) (end 0.498 0.9)
      (stroke (width 0.15) (type solid)) (layer "F.SilkS"))
    (fp_rect (start -2.25 -1.05) (end 2.25 1.05)
      (stroke (width 0.05) (type solid)) (fill none) (layer "F.CrtYd"))
    (fp_line (start -1.601 -0.802) (end -1.601 0.8)
      (stroke (width 0.15) (type solid)) (layer "F.Fab"))
    (fp_line (start -1.601 -0.802) (end 1.6 -0.802)
      (stroke (width 0.15) (type solid)) (layer "F.Fab"))
    (fp_line (start -1.601 0.8) (end 1.6 0.8)
      (stroke (width 0.15) (type solid)) (layer "F.Fab"))
    (fp_line (start 1.6 -0.802) (end 1.6 0.8)
      (stroke (width 0.15) (type solid)) (layer "F.Fab"))
    (pad "1" smd roundrect (at -1.5 0 180) (size 1.2 1.8) (layers "F.Cu" "F.Paste" "F.Mask") (roundrect_rratio 0.15)
      (net 304 "VCC3V3") (pintype "passive"))
    (pad "2" smd roundrect (at 1.499 0 180) (size 1.2 1.8) (layers "F.Cu" "F.Paste" "F.Mask") (roundrect_rratio 0.15)
      (net 143 "3V3_SYS") (pintype "passive"))
  )
)
